FILE_TYPE = CONNECTIVITY;
{Allegro Design Entry HDL 17.2-2016 S081 (4005846) 1/11/2022}
"PAGE_NUMBER" = 54;
0"NC";
1"M_D_CPU1_SA_CA<6:0>";
2"M_D_CPU1_SA_CS_N<3:0>";
3"M_D_CPU1_SA_DQS_DN<9:0>";
4"M_D_CPU1_SA_DQS_DP<9:0>";
5"M_D_CPU1_SB_CA<6:0>";
6"M_D_CPU1_SB_CS_N<3:0>";
7"M_D_CPU1_SB_DQS_DN<9:0>";
8"M_D_CPU1_SB_DQS_DP<9:0>";
9"M_D_CPU1_SB_CB<7:0>";
10"M_D_CPU1_SB_DQ<31:0>";
11"M_D_CPU1_SA_CB<7:0>";
12"M_D_CPU1_SA_DQ<31:0>";
13"M_D_CPU1_CLK_DP<1:0>";
14"M_D_CPU1_CLK_DN<1:0>";
15"M_D_CPU1_SA_DQ<8>";
16"M_D_CPU1_CLK_DN<1>";
17"M_D_CPU1_CLK_DN<0>";
18"M_D_CPU1_CLK_DP<1>";
19"M_D_CPU1_CLK_DP<0>";
20"M_D_CPU1_SA_DQ<31>";
21"M_D_CPU1_SA_DQ<30>";
22"M_D_CPU1_SA_DQ<29>";
23"M_D_CPU1_SA_DQ<28>";
24"M_D_CPU1_SA_DQ<27>";
25"M_D_CPU1_SA_DQ<26>";
26"M_D_CPU1_SA_DQ<25>";
27"M_D_CPU1_SA_DQ<24>";
28"M_D_CPU1_SA_DQ<23>";
29"M_D_CPU1_SA_DQ<22>";
30"M_D_CPU1_SA_DQ<21>";
31"M_D_CPU1_SA_DQ<20>";
32"M_D_CPU1_SA_DQ<19>";
33"M_D_CPU1_SA_DQ<18>";
34"M_D_CPU1_SA_DQ<17>";
35"M_D_CPU1_SA_DQ<16>";
36"M_D_CPU1_SA_DQ<15>";
37"M_D_CPU1_SA_DQ<14>";
38"M_D_CPU1_SA_DQ<13>";
39"M_D_CPU1_SA_DQ<12>";
40"M_D_CPU1_SA_DQ<11>";
41"M_D_CPU1_SA_DQ<10>";
42"M_D_CPU1_SA_DQ<9>";
43"M_D_CPU1_SA_DQ<7>";
44"M_D_CPU1_SA_DQ<6>";
45"M_D_CPU1_SA_DQ<5>";
46"M_D_CPU1_SA_DQ<4>";
47"M_D_CPU1_SA_DQ<3>";
48"M_D_CPU1_SA_DQ<2>";
49"M_D_CPU1_SA_DQ<1>";
50"M_D_CPU1_SA_DQ<0>";
51"M_D_CPU1_SA_CB<7>";
52"M_D_CPU1_SA_CB<6>";
53"M_D_CPU1_SA_CB<5>";
54"M_D_CPU1_SA_CB<4>";
55"M_D_CPU1_SA_CB<3>";
56"M_D_CPU1_SA_CB<2>";
57"M_D_CPU1_SA_CB<1>";
58"M_D_CPU1_SA_CB<0>";
59"M_D_CPU1_SB_DQ<31>";
60"M_D_CPU1_SB_DQ<30>";
61"M_D_CPU1_SB_DQ<29>";
62"M_D_CPU1_SB_DQ<28>";
63"M_D_CPU1_SB_DQ<27>";
64"M_D_CPU1_SB_DQ<26>";
65"M_D_CPU1_SB_DQ<25>";
66"M_D_CPU1_SB_DQ<24>";
67"M_D_CPU1_SB_DQ<23>";
68"M_D_CPU1_SB_DQ<22>";
69"M_D_CPU1_SB_DQ<21>";
70"M_D_CPU1_SB_DQ<20>";
71"M_D_CPU1_SB_DQ<19>";
72"M_D_CPU1_SB_DQ<18>";
73"M_D_CPU1_SB_DQ<17>";
74"M_D_CPU1_SB_DQ<16>";
75"M_D_CPU1_SB_DQ<15>";
76"M_D_CPU1_SB_DQ<14>";
77"M_D_CPU1_SB_DQ<13>";
78"M_D_CPU1_SB_DQ<12>";
79"M_D_CPU1_SB_DQ<11>";
80"M_D_CPU1_SB_DQ<10>";
81"M_D_CPU1_SB_DQ<9>";
82"M_D_CPU1_SB_DQ<8>";
83"M_D_CPU1_SB_DQ<7>";
84"M_D_CPU1_SB_DQ<6>";
85"M_D_CPU1_SB_DQ<5>";
86"M_D_CPU1_SB_DQ<4>";
87"M_D_CPU1_SB_DQ<3>";
88"M_D_CPU1_SB_DQ<2>";
89"M_D_CPU1_SB_DQ<1>";
90"M_D_CPU1_SB_DQ<0>";
91"M_D_CPU1_SB_CB<7>";
92"M_D_CPU1_SB_CB<6>";
93"M_D_CPU1_SB_CB<5>";
94"M_D_CPU1_SB_CB<4>";
95"M_D_CPU1_SB_CB<3>";
96"M_D_CPU1_SB_CB<2>";
97"M_D_CPU1_SB_CB<1>";
98"M_D_CPU1_SB_CB<0>";
99"M_D_CPU1_SB_PAR";
100"M_D_CPU1_SB_DQS_DP<0>";
101"M_D_CPU1_SB_DQS_DP<1>";
102"M_D_CPU1_SB_DQS_DP<2>";
103"M_D_CPU1_SB_DQS_DP<3>";
104"M_D_CPU1_SB_DQS_DP<4>";
105"M_D_CPU1_SB_DQS_DP<5>";
106"M_D_CPU1_SB_DQS_DP<6>";
107"M_D_CPU1_SB_DQS_DP<7>";
108"M_D_CPU1_SB_DQS_DP<8>";
109"M_D_CPU1_SB_DQS_DP<9>";
110"M_D_CPU1_SB_DQS_DN<0>";
111"M_D_CPU1_SB_DQS_DN<1>";
112"M_D_CPU1_SB_DQS_DN<2>";
113"M_D_CPU1_SB_DQS_DN<3>";
114"M_D_CPU1_SB_DQS_DN<4>";
115"M_D_CPU1_SB_DQS_DN<5>";
116"M_D_CPU1_SB_DQS_DN<6>";
117"M_D_CPU1_SB_DQS_DN<7>";
118"M_D_CPU1_SB_DQS_DN<8>";
119"M_D_CPU1_SB_DQS_DN<9>";
120"M_D_CPU1_SB_CS_N<0>";
121"M_D_CPU1_SB_CS_N<1>";
122"M_D_CPU1_SB_CS_N<2>";
123"M_D_CPU1_SB_CS_N<3>";
124"M_D_CPU1_SB_CA<0>";
125"M_D_CPU1_SB_CA<1>";
126"M_D_CPU1_SB_CA<2>";
127"M_D_CPU1_SB_CA<3>";
128"M_D_CPU1_SB_CA<4>";
129"M_D_CPU1_SB_CA<5>";
130"M_D_CPU1_SB_CA<6>";
131"M_D_CPU1_SA_PAR";
132"M_D_CPU1_SA_DQS_DP<0>";
133"M_D_CPU1_SA_DQS_DP<1>";
134"M_D_CPU1_SA_DQS_DP<2>";
135"M_D_CPU1_SA_DQS_DP<3>";
136"M_D_CPU1_SA_DQS_DP<4>";
137"M_D_CPU1_SA_DQS_DP<5>";
138"M_D_CPU1_SA_DQS_DP<6>";
139"M_D_CPU1_SA_DQS_DP<7>";
140"M_D_CPU1_SA_DQS_DP<8>";
141"M_D_CPU1_SA_DQS_DP<9>";
142"M_D_CPU1_SA_DQS_DN<0>";
143"M_D_CPU1_SA_DQS_DN<1>";
144"M_D_CPU1_SA_DQS_DN<2>";
145"M_D_CPU1_SA_DQS_DN<3>";
146"M_D_CPU1_SA_DQS_DN<4>";
147"M_D_CPU1_SA_DQS_DN<5>";
148"M_D_CPU1_SA_DQS_DN<6>";
149"M_D_CPU1_SA_DQS_DN<7>";
150"M_D_CPU1_SA_DQS_DN<8>";
151"M_D_CPU1_SA_DQS_DN<9>";
152"M_D_CPU1_SA_CS_N<0>";
153"M_D_CPU1_SA_CS_N<1>";
154"M_D_CPU1_SA_CS_N<2>";
155"M_D_CPU1_SA_CS_N<3>";
156"M_D_CPU1_SA_CA<0>";
157"M_D_CPU1_SA_CA<1>";
158"M_D_CPU1_SA_CA<2>";
159"M_D_CPU1_SA_CA<3>";
160"M_D_CPU1_SA_CA<4>";
161"M_D_CPU1_SA_CA<5>";
162"M_D_CPU1_SA_CA<6>";
163"M_D_CPU1_SB_RSP<0>";
164"M_D_CPU1_SB_RSP<1>";
165"M_D_CPU1_SA_RSP<0>";
166"M_D_CPU1_SA_RSP<1>";
167"M_D_CPU1_ALERT_N";
%"TAP"
"1","(2600,0)","0","standard","I100";
;
CDS_LIB"standard"
BODY_TYPE"PLUMBING"
HDL_TAP"TRUE";
"B \NAC \NWC"6;
"S \NAC"
BN"3"123;
%"TAP"
"1","(2600,150)","0","standard","I101";
;
CDS_LIB"standard"
BODY_TYPE"PLUMBING"
HDL_TAP"TRUE";
"B \NAC \NWC"2;
"S \NAC"
BN"0"152;
%"TAP"
"1","(2600,200)","0","standard","I102";
;
CDS_LIB"standard"
BODY_TYPE"PLUMBING"
HDL_TAP"TRUE";
"B \NAC \NWC"2;
"S \NAC"
BN"1"153;
%"TAP"
"1","(2600,300)","0","standard","I103";
;
CDS_LIB"standard"
BODY_TYPE"PLUMBING"
HDL_TAP"TRUE";
"B \NAC \NWC"2;
"S \NAC"
BN"3"155;
%"TAP"
"1","(2600,250)","0","standard","I104";
;
CDS_LIB"standard"
BODY_TYPE"PLUMBING"
HDL_TAP"TRUE";
"B \NAC \NWC"2;
"S \NAC"
BN"2"154;
%"TAP"
"1","(2600,500)","0","standard","I105";
;
CDS_LIB"standard"
BODY_TYPE"PLUMBING"
HDL_TAP"TRUE";
"B \NAC \NWC"5;
"S \NAC"
BN"0"124;
%"TAP"
"1","(2600,550)","0","standard","I106";
;
CDS_LIB"standard"
BODY_TYPE"PLUMBING"
HDL_TAP"TRUE";
"B \NAC \NWC"5;
"S \NAC"
BN"1"125;
%"TAP"
"1","(2600,600)","0","standard","I107";
;
CDS_LIB"standard"
BODY_TYPE"PLUMBING"
HDL_TAP"TRUE";
"B \NAC \NWC"5;
"S \NAC"
BN"2"126;
%"TAP"
"1","(2600,700)","0","standard","I108";
;
CDS_LIB"standard"
BODY_TYPE"PLUMBING"
HDL_TAP"TRUE";
"B \NAC \NWC"5;
"S \NAC"
BN"4"128;
%"TAP"
"1","(2600,650)","0","standard","I109";
;
CDS_LIB"standard"
BODY_TYPE"PLUMBING"
HDL_TAP"TRUE";
"B \NAC \NWC"5;
"S \NAC"
BN"3"127;
%"TAP"
"1","(-825,-200)","2","standard","I11";
;
CDS_LIB"standard"
BODY_TYPE"PLUMBING"
HDL_TAP"TRUE";
"B \NAC \NWC"9;
"S \NAC"
BN"3"95;
%"TAP"
"1","(2600,750)","0","standard","I110";
;
CDS_LIB"standard"
BODY_TYPE"PLUMBING"
HDL_TAP"TRUE";
"B \NAC \NWC"5;
"S \NAC"
BN"5"129;
%"TAP"
"1","(2600,800)","0","standard","I111";
;
CDS_LIB"standard"
BODY_TYPE"PLUMBING"
HDL_TAP"TRUE";
"B \NAC \NWC"5;
"S \NAC"
BN"6"130;
%"TAP"
"1","(2600,1100)","0","standard","I112";
;
CDS_LIB"standard"
BODY_TYPE"PLUMBING"
HDL_TAP"TRUE";
"B \NAC \NWC"1;
"S \NAC"
BN"2"158;
%"TAP"
"1","(2600,1050)","0","standard","I113";
;
CDS_LIB"standard"
BODY_TYPE"PLUMBING"
HDL_TAP"TRUE";
"B \NAC \NWC"1;
"S \NAC"
BN"1"157;
%"TAP"
"1","(2600,1000)","0","standard","I114";
;
CDS_LIB"standard"
BODY_TYPE"PLUMBING"
HDL_TAP"TRUE";
"B \NAC \NWC"1;
"S \NAC"
BN"0"156;
%"TAP"
"1","(2600,1150)","0","standard","I115";
;
CDS_LIB"standard"
BODY_TYPE"PLUMBING"
HDL_TAP"TRUE";
"B \NAC \NWC"1;
"S \NAC"
BN"3"159;
%"TAP"
"1","(2600,1200)","0","standard","I116";
;
CDS_LIB"standard"
BODY_TYPE"PLUMBING"
HDL_TAP"TRUE";
"B \NAC \NWC"1;
"S \NAC"
BN"4"160;
%"TAP"
"1","(2600,1250)","0","standard","I117";
;
CDS_LIB"standard"
BODY_TYPE"PLUMBING"
HDL_TAP"TRUE";
"B \NAC \NWC"1;
"S \NAC"
BN"5"161;
%"TAP"
"1","(2600,1300)","0","standard","I118";
;
CDS_LIB"standard"
BODY_TYPE"PLUMBING"
HDL_TAP"TRUE";
"B \NAC \NWC"1;
"S \NAC"
BN"6"162;
%"TAP"
"1","(2600,1450)","0","standard","I119";
;
CDS_LIB"standard"
BODY_TYPE"PLUMBING"
HDL_TAP"TRUE";
"B \NAC \NWC"7;
"S \NAC"
BN"0"110;
%"TAP"
"1","(-825,-250)","2","standard","I12";
;
CDS_LIB"standard"
BODY_TYPE"PLUMBING"
HDL_TAP"TRUE";
"B \NAC \NWC"9;
"S \NAC"
BN"2"96;
%"TAP"
"1","(2600,1500)","0","standard","I120";
;
CDS_LIB"standard"
BODY_TYPE"PLUMBING"
HDL_TAP"TRUE";
"B \NAC \NWC"7;
"S \NAC"
BN"1"111;
%"TAP"
"1","(2600,1600)","0","standard","I121";
;
CDS_LIB"standard"
BODY_TYPE"PLUMBING"
HDL_TAP"TRUE";
"B \NAC \NWC"7;
"S \NAC"
BN"3"113;
%"TAP"
"1","(2600,1550)","0","standard","I122";
;
CDS_LIB"standard"
BODY_TYPE"PLUMBING"
HDL_TAP"TRUE";
"B \NAC \NWC"7;
"S \NAC"
BN"2"112;
%"TAP"
"1","(2600,1650)","0","standard","I123";
;
CDS_LIB"standard"
BODY_TYPE"PLUMBING"
HDL_TAP"TRUE";
"B \NAC \NWC"7;
"S \NAC"
BN"4"114;
%"TAP"
"1","(2600,1700)","0","standard","I124";
;
CDS_LIB"standard"
BODY_TYPE"PLUMBING"
HDL_TAP"TRUE";
"B \NAC \NWC"7;
"S \NAC"
BN"5"115;
%"TAP"
"1","(2600,1750)","0","standard","I125";
;
CDS_LIB"standard"
BODY_TYPE"PLUMBING"
HDL_TAP"TRUE";
"B \NAC \NWC"7;
"S \NAC"
BN"6"116;
%"TAP"
"1","(2600,1850)","0","standard","I126";
;
CDS_LIB"standard"
BODY_TYPE"PLUMBING"
HDL_TAP"TRUE";
"B \NAC \NWC"7;
"S \NAC"
BN"8"118;
%"TAP"
"1","(2600,1800)","0","standard","I127";
;
CDS_LIB"standard"
BODY_TYPE"PLUMBING"
HDL_TAP"TRUE";
"B \NAC \NWC"7;
"S \NAC"
BN"7"117;
%"TAP"
"1","(2600,1900)","0","standard","I128";
;
CDS_LIB"standard"
BODY_TYPE"PLUMBING"
HDL_TAP"TRUE";
"B \NAC \NWC"7;
"S \NAC"
BN"9"119;
%"TAP"
"1","(2600,2000)","0","standard","I129";
;
CDS_LIB"standard"
BODY_TYPE"PLUMBING"
HDL_TAP"TRUE";
"B \NAC \NWC"8;
"S \NAC"
BN"0"100;
%"TAP"
"1","(-825,-100)","2","standard","I13";
;
CDS_LIB"standard"
BODY_TYPE"PLUMBING"
HDL_TAP"TRUE";
"B \NAC \NWC"9;
"S \NAC"
BN"5"93;
%"TAP"
"1","(2600,2100)","0","standard","I130";
;
CDS_LIB"standard"
BODY_TYPE"PLUMBING"
HDL_TAP"TRUE";
"B \NAC \NWC"8;
"S \NAC"
BN"2"102;
%"TAP"
"1","(2600,2050)","0","standard","I131";
;
CDS_LIB"standard"
BODY_TYPE"PLUMBING"
HDL_TAP"TRUE";
"B \NAC \NWC"8;
"S \NAC"
BN"1"101;
%"TAP"
"1","(2600,2150)","0","standard","I132";
;
CDS_LIB"standard"
BODY_TYPE"PLUMBING"
HDL_TAP"TRUE";
"B \NAC \NWC"8;
"S \NAC"
BN"3"103;
%"TAP"
"1","(2600,2250)","0","standard","I133";
;
CDS_LIB"standard"
BODY_TYPE"PLUMBING"
HDL_TAP"TRUE";
"B \NAC \NWC"8;
"S \NAC"
BN"5"105;
%"TAP"
"1","(2600,2200)","0","standard","I134";
;
CDS_LIB"standard"
BODY_TYPE"PLUMBING"
HDL_TAP"TRUE";
"B \NAC \NWC"8;
"S \NAC"
BN"4"104;
%"TAP"
"1","(2600,2350)","0","standard","I135";
;
CDS_LIB"standard"
BODY_TYPE"PLUMBING"
HDL_TAP"TRUE";
"B \NAC \NWC"8;
"S \NAC"
BN"7"107;
%"TAP"
"1","(2600,2300)","0","standard","I136";
;
CDS_LIB"standard"
BODY_TYPE"PLUMBING"
HDL_TAP"TRUE";
"B \NAC \NWC"8;
"S \NAC"
BN"6"106;
%"TAP"
"1","(2600,2400)","0","standard","I137";
;
CDS_LIB"standard"
BODY_TYPE"PLUMBING"
HDL_TAP"TRUE";
"B \NAC \NWC"8;
"S \NAC"
BN"8"108;
%"TAP"
"1","(2600,2450)","0","standard","I138";
;
CDS_LIB"standard"
BODY_TYPE"PLUMBING"
HDL_TAP"TRUE";
"B \NAC \NWC"8;
"S \NAC"
BN"9"109;
%"TAP"
"1","(2600,2600)","0","standard","I139";
;
CDS_LIB"standard"
BODY_TYPE"PLUMBING"
HDL_TAP"TRUE";
"B \NAC \NWC"3;
"S \NAC"
BN"0"142;
%"TAP"
"1","(-825,-150)","2","standard","I14";
;
CDS_LIB"standard"
BODY_TYPE"PLUMBING"
HDL_TAP"TRUE";
"B \NAC \NWC"9;
"S \NAC"
BN"4"94;
%"TAP"
"1","(2600,2650)","0","standard","I140";
;
CDS_LIB"standard"
BODY_TYPE"PLUMBING"
HDL_TAP"TRUE";
"B \NAC \NWC"3;
"S \NAC"
BN"1"143;
%"TAP"
"1","(2600,2750)","0","standard","I141";
;
CDS_LIB"standard"
BODY_TYPE"PLUMBING"
HDL_TAP"TRUE";
"B \NAC \NWC"3;
"S \NAC"
BN"3"145;
%"TAP"
"1","(2600,2700)","0","standard","I142";
;
CDS_LIB"standard"
BODY_TYPE"PLUMBING"
HDL_TAP"TRUE";
"B \NAC \NWC"3;
"S \NAC"
BN"2"144;
%"TAP"
"1","(2600,2850)","0","standard","I143";
;
CDS_LIB"standard"
BODY_TYPE"PLUMBING"
HDL_TAP"TRUE";
"B \NAC \NWC"3;
"S \NAC"
BN"5"147;
%"TAP"
"1","(2600,2800)","0","standard","I144";
;
CDS_LIB"standard"
BODY_TYPE"PLUMBING"
HDL_TAP"TRUE";
"B \NAC \NWC"3;
"S \NAC"
BN"4"146;
%"TAP"
"1","(2600,2900)","0","standard","I145";
;
CDS_LIB"standard"
BODY_TYPE"PLUMBING"
HDL_TAP"TRUE";
"B \NAC \NWC"3;
"S \NAC"
BN"6"148;
%"TAP"
"1","(2600,2950)","0","standard","I146";
;
CDS_LIB"standard"
BODY_TYPE"PLUMBING"
HDL_TAP"TRUE";
"B \NAC \NWC"3;
"S \NAC"
BN"7"149;
%"TAP"
"1","(2600,3000)","0","standard","I147";
;
CDS_LIB"standard"
BODY_TYPE"PLUMBING"
HDL_TAP"TRUE";
"B \NAC \NWC"3;
"S \NAC"
BN"8"150;
%"TAP"
"1","(2600,3050)","0","standard","I148";
;
CDS_LIB"standard"
BODY_TYPE"PLUMBING"
HDL_TAP"TRUE";
"B \NAC \NWC"3;
"S \NAC"
BN"9"151;
%"TAP"
"1","(2600,3150)","0","standard","I149";
;
CDS_LIB"standard"
BODY_TYPE"PLUMBING"
HDL_TAP"TRUE";
"B \NAC \NWC"4;
"S \NAC"
BN"0"132;
%"TAP"
"1","(-825,-50)","2","standard","I15";
;
CDS_LIB"standard"
BODY_TYPE"PLUMBING"
HDL_TAP"TRUE";
"B \NAC \NWC"9;
"S \NAC"
BN"6"92;
%"TAP"
"1","(2600,3200)","0","standard","I150";
;
CDS_LIB"standard"
BODY_TYPE"PLUMBING"
HDL_TAP"TRUE";
"B \NAC \NWC"4;
"S \NAC"
BN"1"133;
%"TAP"
"1","(2600,3250)","0","standard","I151";
;
CDS_LIB"standard"
BODY_TYPE"PLUMBING"
HDL_TAP"TRUE";
"B \NAC \NWC"4;
"S \NAC"
BN"2"134;
%"TAP"
"1","(2600,3300)","0","standard","I152";
;
CDS_LIB"standard"
BODY_TYPE"PLUMBING"
HDL_TAP"TRUE";
"B \NAC \NWC"4;
"S \NAC"
BN"3"135;
%"TAP"
"1","(2600,3400)","0","standard","I153";
;
CDS_LIB"standard"
BODY_TYPE"PLUMBING"
HDL_TAP"TRUE";
"B \NAC \NWC"4;
"S \NAC"
BN"5"137;
%"TAP"
"1","(2600,3350)","0","standard","I154";
;
CDS_LIB"standard"
BODY_TYPE"PLUMBING"
HDL_TAP"TRUE";
"B \NAC \NWC"4;
"S \NAC"
BN"4"136;
%"TAP"
"1","(2600,3450)","0","standard","I155";
;
CDS_LIB"standard"
BODY_TYPE"PLUMBING"
HDL_TAP"TRUE";
"B \NAC \NWC"4;
"S \NAC"
BN"6"138;
%"TAP"
"1","(2600,3500)","0","standard","I156";
;
CDS_LIB"standard"
BODY_TYPE"PLUMBING"
HDL_TAP"TRUE";
"B \NAC \NWC"4;
"S \NAC"
BN"7"139;
%"TAP"
"1","(2600,3550)","0","standard","I157";
;
CDS_LIB"standard"
BODY_TYPE"PLUMBING"
HDL_TAP"TRUE";
"B \NAC \NWC"4;
"S \NAC"
BN"8"140;
%"TAP"
"1","(2600,3600)","0","standard","I158";
;
CDS_LIB"standard"
BODY_TYPE"PLUMBING"
HDL_TAP"TRUE";
"B \NAC \NWC"4;
"S \NAC"
BN"9"141;
%"TAP"
"1","(-825,0)","2","standard","I16";
;
CDS_LIB"standard"
BODY_TYPE"PLUMBING"
HDL_TAP"TRUE";
"B \NAC \NWC"9;
"S \NAC"
BN"7"91;
%"TAP"
"1","(-825,50)","2","standard","I17";
;
CDS_LIB"standard"
BODY_TYPE"PLUMBING"
HDL_TAP"TRUE";
"B \NAC \NWC"10;
"S \NAC"
BN"0"90;
%"TAP"
"1","(-825,100)","2","standard","I18";
;
CDS_LIB"standard"
BODY_TYPE"PLUMBING"
HDL_TAP"TRUE";
"B \NAC \NWC"10;
"S \NAC"
BN"1"89;
%"TAP"
"1","(-825,150)","2","standard","I19";
;
CDS_LIB"standard"
BODY_TYPE"PLUMBING"
HDL_TAP"TRUE";
"B \NAC \NWC"10;
"S \NAC"
BN"2"88;
%"TAP"
"1","(-825,200)","2","standard","I20";
;
CDS_LIB"standard"
BODY_TYPE"PLUMBING"
HDL_TAP"TRUE";
"B \NAC \NWC"10;
"S \NAC"
BN"3"87;
%"TAP"
"1","(-825,250)","2","standard","I21";
;
CDS_LIB"standard"
BODY_TYPE"PLUMBING"
HDL_TAP"TRUE";
"B \NAC \NWC"10;
"S \NAC"
BN"4"86;
%"TAP"
"1","(-825,300)","2","standard","I22";
;
CDS_LIB"standard"
BODY_TYPE"PLUMBING"
HDL_TAP"TRUE";
"B \NAC \NWC"10;
"S \NAC"
BN"5"85;
%"TAP"
"1","(-825,350)","2","standard","I23";
;
CDS_LIB"standard"
BODY_TYPE"PLUMBING"
HDL_TAP"TRUE";
"B \NAC \NWC"10;
"S \NAC"
BN"6"84;
%"TAP"
"1","(-825,400)","2","standard","I24";
;
CDS_LIB"standard"
BODY_TYPE"PLUMBING"
HDL_TAP"TRUE";
"B \NAC \NWC"10;
"S \NAC"
BN"7"83;
%"TAP"
"1","(-825,450)","2","standard","I25";
;
CDS_LIB"standard"
BODY_TYPE"PLUMBING"
HDL_TAP"TRUE";
"B \NAC \NWC"10;
"S \NAC"
BN"8"82;
%"TAP"
"1","(-825,500)","2","standard","I26";
;
CDS_LIB"standard"
BODY_TYPE"PLUMBING"
HDL_TAP"TRUE";
"B \NAC \NWC"10;
"S \NAC"
BN"9"81;
%"TAP"
"1","(-825,550)","2","standard","I27";
;
CDS_LIB"standard"
BODY_TYPE"PLUMBING"
HDL_TAP"TRUE";
"B \NAC \NWC"10;
"S \NAC"
BN"10"80;
%"TAP"
"1","(-825,600)","2","standard","I28";
;
CDS_LIB"standard"
BODY_TYPE"PLUMBING"
HDL_TAP"TRUE";
"B \NAC \NWC"10;
"S \NAC"
BN"11"79;
%"TAP"
"1","(-825,650)","2","standard","I29";
;
CDS_LIB"standard"
BODY_TYPE"PLUMBING"
HDL_TAP"TRUE";
"B \NAC \NWC"10;
"S \NAC"
BN"12"78;
%"TAP"
"1","(-825,-600)","2","standard","I3";
;
CDS_LIB"standard"
BODY_TYPE"PLUMBING"
HDL_TAP"TRUE";
"B \NAC \NWC"14;
"S \NAC"
BN"0"17;
%"TAP"
"1","(-825,700)","2","standard","I30";
;
CDS_LIB"standard"
BODY_TYPE"PLUMBING"
HDL_TAP"TRUE";
"B \NAC \NWC"10;
"S \NAC"
BN"13"77;
%"TAP"
"1","(-825,750)","2","standard","I31";
;
CDS_LIB"standard"
BODY_TYPE"PLUMBING"
HDL_TAP"TRUE";
"B \NAC \NWC"10;
"S \NAC"
BN"14"76;
%"TAP"
"1","(-825,800)","2","standard","I32";
;
CDS_LIB"standard"
BODY_TYPE"PLUMBING"
HDL_TAP"TRUE";
"B \NAC \NWC"10;
"S \NAC"
BN"15"75;
%"TAP"
"1","(-825,850)","2","standard","I33";
;
CDS_LIB"standard"
BODY_TYPE"PLUMBING"
HDL_TAP"TRUE";
"B \NAC \NWC"10;
"S \NAC"
BN"16"74;
%"TAP"
"1","(-825,900)","2","standard","I34";
;
CDS_LIB"standard"
BODY_TYPE"PLUMBING"
HDL_TAP"TRUE";
"B \NAC \NWC"10;
"S \NAC"
BN"17"73;
%"TAP"
"1","(-825,950)","2","standard","I35";
;
CDS_LIB"standard"
BODY_TYPE"PLUMBING"
HDL_TAP"TRUE";
"B \NAC \NWC"10;
"S \NAC"
BN"18"72;
%"TAP"
"1","(-825,1000)","2","standard","I36";
;
CDS_LIB"standard"
BODY_TYPE"PLUMBING"
HDL_TAP"TRUE";
"B \NAC \NWC"10;
"S \NAC"
BN"19"71;
%"TAP"
"1","(-825,1050)","2","standard","I37";
;
CDS_LIB"standard"
BODY_TYPE"PLUMBING"
HDL_TAP"TRUE";
"B \NAC \NWC"10;
"S \NAC"
BN"20"70;
%"TAP"
"1","(-825,1100)","2","standard","I38";
;
CDS_LIB"standard"
BODY_TYPE"PLUMBING"
HDL_TAP"TRUE";
"B \NAC \NWC"10;
"S \NAC"
BN"21"69;
%"TAP"
"1","(-825,1150)","2","standard","I39";
;
CDS_LIB"standard"
BODY_TYPE"PLUMBING"
HDL_TAP"TRUE";
"B \NAC \NWC"10;
"S \NAC"
BN"22"68;
%"TAP"
"1","(-825,-500)","2","standard","I4";
;
CDS_LIB"standard"
BODY_TYPE"PLUMBING"
HDL_TAP"TRUE";
"B \NAC \NWC"13;
"S \NAC"
BN"0"19;
%"TAP"
"1","(-825,1200)","2","standard","I40";
;
CDS_LIB"standard"
BODY_TYPE"PLUMBING"
HDL_TAP"TRUE";
"B \NAC \NWC"10;
"S \NAC"
BN"23"67;
%"TAP"
"1","(-825,1250)","2","standard","I41";
;
CDS_LIB"standard"
BODY_TYPE"PLUMBING"
HDL_TAP"TRUE";
"B \NAC \NWC"10;
"S \NAC"
BN"24"66;
%"TAP"
"1","(-825,1300)","2","standard","I42";
;
CDS_LIB"standard"
BODY_TYPE"PLUMBING"
HDL_TAP"TRUE";
"B \NAC \NWC"10;
"S \NAC"
BN"25"65;
%"TAP"
"1","(-825,1350)","2","standard","I43";
;
CDS_LIB"standard"
BODY_TYPE"PLUMBING"
HDL_TAP"TRUE";
"B \NAC \NWC"10;
"S \NAC"
BN"26"64;
%"TAP"
"1","(-825,1400)","2","standard","I44";
;
CDS_LIB"standard"
BODY_TYPE"PLUMBING"
HDL_TAP"TRUE";
"B \NAC \NWC"10;
"S \NAC"
BN"27"63;
%"TAP"
"1","(-825,1450)","2","standard","I45";
;
CDS_LIB"standard"
BODY_TYPE"PLUMBING"
HDL_TAP"TRUE";
"B \NAC \NWC"10;
"S \NAC"
BN"28"62;
%"TAP"
"1","(-825,1500)","2","standard","I46";
;
CDS_LIB"standard"
BODY_TYPE"PLUMBING"
HDL_TAP"TRUE";
"B \NAC \NWC"10;
"S \NAC"
BN"29"61;
%"TAP"
"1","(-825,1550)","2","standard","I47";
;
CDS_LIB"standard"
BODY_TYPE"PLUMBING"
HDL_TAP"TRUE";
"B \NAC \NWC"10;
"S \NAC"
BN"30"60;
%"TAP"
"1","(-825,1600)","2","standard","I48";
;
CDS_LIB"standard"
BODY_TYPE"PLUMBING"
HDL_TAP"TRUE";
"B \NAC \NWC"10;
"S \NAC"
BN"31"59;
%"TAP"
"1","(-825,1650)","2","standard","I49";
;
CDS_LIB"standard"
BODY_TYPE"PLUMBING"
HDL_TAP"TRUE";
"B \NAC \NWC"11;
"S \NAC"
BN"0"58;
%"TAP"
"1","(-825,-550)","2","standard","I5";
;
CDS_LIB"standard"
BODY_TYPE"PLUMBING"
HDL_TAP"TRUE";
"B \NAC \NWC"14;
"S \NAC"
BN"1"16;
%"TAP"
"1","(-825,1700)","2","standard","I50";
;
CDS_LIB"standard"
BODY_TYPE"PLUMBING"
HDL_TAP"TRUE";
"B \NAC \NWC"11;
"S \NAC"
BN"1"57;
%"TAP"
"1","(-825,1750)","2","standard","I53";
;
CDS_LIB"standard"
BODY_TYPE"PLUMBING"
HDL_TAP"TRUE";
"B \NAC \NWC"11;
"S \NAC"
BN"2"56;
%"TAP"
"1","(-825,1800)","2","standard","I54";
;
CDS_LIB"standard"
BODY_TYPE"PLUMBING"
HDL_TAP"TRUE";
"B \NAC \NWC"11;
"S \NAC"
BN"3"55;
%"TAP"
"1","(-825,1850)","2","standard","I55";
;
CDS_LIB"standard"
BODY_TYPE"PLUMBING"
HDL_TAP"TRUE";
"B \NAC \NWC"11;
"S \NAC"
BN"4"54;
%"TAP"
"1","(-825,1900)","2","standard","I56";
;
CDS_LIB"standard"
BODY_TYPE"PLUMBING"
HDL_TAP"TRUE";
"B \NAC \NWC"11;
"S \NAC"
BN"5"53;
%"TAP"
"1","(-825,1950)","2","standard","I57";
;
CDS_LIB"standard"
BODY_TYPE"PLUMBING"
HDL_TAP"TRUE";
"B \NAC \NWC"11;
"S \NAC"
BN"6"52;
%"TAP"
"1","(-825,2000)","2","standard","I58";
;
CDS_LIB"standard"
BODY_TYPE"PLUMBING"
HDL_TAP"TRUE";
"B \NAC \NWC"11;
"S \NAC"
BN"7"51;
%"TAP"
"1","(-825,2100)","2","standard","I59";
;
CDS_LIB"standard"
BODY_TYPE"PLUMBING"
HDL_TAP"TRUE";
"B \NAC \NWC"12;
"S \NAC"
BN"1"49;
%"TAP"
"1","(-825,-450)","2","standard","I6";
;
CDS_LIB"standard"
BODY_TYPE"PLUMBING"
HDL_TAP"TRUE";
"B \NAC \NWC"13;
"S \NAC"
BN"1"18;
%"TAP"
"1","(-825,2050)","2","standard","I60";
;
CDS_LIB"standard"
BODY_TYPE"PLUMBING"
HDL_TAP"TRUE";
"B \NAC \NWC"12;
"S \NAC"
BN"0"50;
%"TAP"
"1","(-825,2150)","2","standard","I61";
;
CDS_LIB"standard"
BODY_TYPE"PLUMBING"
HDL_TAP"TRUE";
"B \NAC \NWC"12;
"S \NAC"
BN"2"48;
%"TAP"
"1","(-825,2200)","2","standard","I62";
;
CDS_LIB"standard"
BODY_TYPE"PLUMBING"
HDL_TAP"TRUE";
"B \NAC \NWC"12;
"S \NAC"
BN"3"47;
%"TAP"
"1","(-825,2250)","2","standard","I63";
;
CDS_LIB"standard"
BODY_TYPE"PLUMBING"
HDL_TAP"TRUE";
"B \NAC \NWC"12;
"S \NAC"
BN"4"46;
%"TAP"
"1","(-825,2300)","2","standard","I64";
;
CDS_LIB"standard"
BODY_TYPE"PLUMBING"
HDL_TAP"TRUE";
"B \NAC \NWC"12;
"S \NAC"
BN"5"45;
%"TAP"
"1","(-825,2350)","2","standard","I65";
;
CDS_LIB"standard"
BODY_TYPE"PLUMBING"
HDL_TAP"TRUE";
"B \NAC \NWC"12;
"S \NAC"
BN"6"44;
%"TAP"
"1","(-825,2400)","2","standard","I66";
;
CDS_LIB"standard"
BODY_TYPE"PLUMBING"
HDL_TAP"TRUE";
"B \NAC \NWC"12;
"S \NAC"
BN"7"43;
%"TAP"
"1","(-825,2450)","2","standard","I67";
;
CDS_LIB"standard"
BODY_TYPE"PLUMBING"
HDL_TAP"TRUE";
"B \NAC \NWC"12;
"S \NAC"
BN"8"15;
%"TAP"
"1","(-825,2500)","2","standard","I68";
;
CDS_LIB"standard"
BODY_TYPE"PLUMBING"
HDL_TAP"TRUE";
"B \NAC \NWC"12;
"S \NAC"
BN"9"42;
%"TAP"
"1","(-825,2550)","2","standard","I69";
;
CDS_LIB"standard"
BODY_TYPE"PLUMBING"
HDL_TAP"TRUE";
"B \NAC \NWC"12;
"S \NAC"
BN"10"41;
%"TAP"
"1","(-825,-350)","2","standard","I7";
;
CDS_LIB"standard"
BODY_TYPE"PLUMBING"
HDL_TAP"TRUE";
"B \NAC \NWC"9;
"S \NAC"
BN"0"98;
%"TAP"
"1","(-825,2600)","2","standard","I70";
;
CDS_LIB"standard"
BODY_TYPE"PLUMBING"
HDL_TAP"TRUE";
"B \NAC \NWC"12;
"S \NAC"
BN"11"40;
%"TAP"
"1","(-825,2650)","2","standard","I71";
;
CDS_LIB"standard"
BODY_TYPE"PLUMBING"
HDL_TAP"TRUE";
"B \NAC \NWC"12;
"S \NAC"
BN"12"39;
%"TAP"
"1","(-825,2700)","2","standard","I72";
;
CDS_LIB"standard"
BODY_TYPE"PLUMBING"
HDL_TAP"TRUE";
"B \NAC \NWC"12;
"S \NAC"
BN"13"38;
%"TAP"
"1","(-825,2750)","2","standard","I73";
;
CDS_LIB"standard"
BODY_TYPE"PLUMBING"
HDL_TAP"TRUE";
"B \NAC \NWC"12;
"S \NAC"
BN"14"37;
%"TAP"
"1","(-825,2800)","2","standard","I74";
;
CDS_LIB"standard"
BODY_TYPE"PLUMBING"
HDL_TAP"TRUE";
"B \NAC \NWC"12;
"S \NAC"
BN"15"36;
%"TAP"
"1","(-825,2850)","2","standard","I75";
;
CDS_LIB"standard"
BODY_TYPE"PLUMBING"
HDL_TAP"TRUE";
"B \NAC \NWC"12;
"S \NAC"
BN"16"35;
%"TAP"
"1","(-825,2900)","2","standard","I76";
;
CDS_LIB"standard"
BODY_TYPE"PLUMBING"
HDL_TAP"TRUE";
"B \NAC \NWC"12;
"S \NAC"
BN"17"34;
%"TAP"
"1","(-825,2950)","2","standard","I77";
;
CDS_LIB"standard"
BODY_TYPE"PLUMBING"
HDL_TAP"TRUE";
"B \NAC \NWC"12;
"S \NAC"
BN"18"33;
%"TAP"
"1","(-825,3000)","2","standard","I78";
;
CDS_LIB"standard"
BODY_TYPE"PLUMBING"
HDL_TAP"TRUE";
"B \NAC \NWC"12;
"S \NAC"
BN"19"32;
%"TAP"
"1","(-825,3050)","2","standard","I79";
;
CDS_LIB"standard"
BODY_TYPE"PLUMBING"
HDL_TAP"TRUE";
"B \NAC \NWC"12;
"S \NAC"
BN"20"31;
%"TAP"
"1","(-825,-300)","2","standard","I8";
;
CDS_LIB"standard"
BODY_TYPE"PLUMBING"
HDL_TAP"TRUE";
"B \NAC \NWC"9;
"S \NAC"
BN"1"97;
%"TAP"
"1","(-825,3100)","2","standard","I80";
;
CDS_LIB"standard"
BODY_TYPE"PLUMBING"
HDL_TAP"TRUE";
"B \NAC \NWC"12;
"S \NAC"
BN"21"30;
%"TAP"
"1","(-825,3150)","2","standard","I81";
;
CDS_LIB"standard"
BODY_TYPE"PLUMBING"
HDL_TAP"TRUE";
"B \NAC \NWC"12;
"S \NAC"
BN"22"29;
%"TAP"
"1","(-825,3250)","2","standard","I82";
;
CDS_LIB"standard"
BODY_TYPE"PLUMBING"
HDL_TAP"TRUE";
"B \NAC \NWC"12;
"S \NAC"
BN"24"27;
%"TAP"
"1","(-825,3200)","2","standard","I83";
;
CDS_LIB"standard"
BODY_TYPE"PLUMBING"
HDL_TAP"TRUE";
"B \NAC \NWC"12;
"S \NAC"
BN"23"28;
%"TAP"
"1","(-825,3300)","2","standard","I84";
;
CDS_LIB"standard"
BODY_TYPE"PLUMBING"
HDL_TAP"TRUE";
"B \NAC \NWC"12;
"S \NAC"
BN"25"26;
%"TAP"
"1","(-825,3350)","2","standard","I85";
;
CDS_LIB"standard"
BODY_TYPE"PLUMBING"
HDL_TAP"TRUE";
"B \NAC \NWC"12;
"S \NAC"
BN"26"25;
%"TAP"
"1","(-825,3400)","2","standard","I86";
;
CDS_LIB"standard"
BODY_TYPE"PLUMBING"
HDL_TAP"TRUE";
"B \NAC \NWC"12;
"S \NAC"
BN"27"24;
%"TAP"
"1","(-825,3450)","2","standard","I87";
;
CDS_LIB"standard"
BODY_TYPE"PLUMBING"
HDL_TAP"TRUE";
"B \NAC \NWC"12;
"S \NAC"
BN"28"23;
%"TAP"
"1","(-825,3500)","2","standard","I88";
;
CDS_LIB"standard"
BODY_TYPE"PLUMBING"
HDL_TAP"TRUE";
"B \NAC \NWC"12;
"S \NAC"
BN"29"22;
%"TAP"
"1","(-825,3550)","2","standard","I89";
;
CDS_LIB"standard"
BODY_TYPE"PLUMBING"
HDL_TAP"TRUE";
"B \NAC \NWC"12;
"S \NAC"
BN"30"21;
%"TAP"
"1","(-825,3600)","2","standard","I90";
;
CDS_LIB"standard"
BODY_TYPE"PLUMBING"
HDL_TAP"TRUE";
"B \NAC \NWC"12;
"S \NAC"
BN"31"20;
%"SOCKET4677_AZIF0045P001C01CS"
"11","(900,1500)","0","pure_quanta","I91";
;
PART_NUMBER"DGA^7000023"
PART_TYPE"SMLF"
MATERIAL"IO"
VALUE"SOCKET4677_AZIF0045-P001C01CS"
$LOCATION"U1"
CDS_LIB"pure_quanta"
NEEDS_NO_SIZE"TRUE"
CDS_LMAN_SYM_OUTLINE"-1100,2250,1050,-2250"
CDS_LOCATION"U1"
$SEC"11"
CDS_SEC"11";
"DDR3_SB_PAR"
$PN"AH42"99;
"DDR3_SB_ECC0"
$PN"AK38"98;
"DDR3_SB_ECC1"
$PN"AL37"97;
"DDR3_SB_ECC2"
$PN"AP38"96;
"DDR3_SB_ECC3"
$PN"AN37"95;
"DDR3_SB_ECC4"
$PN"AL41"94;
"DDR3_SB_ECC5"
$PN"AK40"93;
"DDR3_SB_ECC6"
$PN"AN41"92;
"DDR3_SB_ECC7"
$PN"AP40"91;
"DDR3_SB_DQS_DP0"
$PN"AL33"100;
"DDR3_SB_DQS_DP1"
$PN"AL27"101;
"DDR3_SB_DQS_DP2"
$PN"AD24"102;
"DDR3_SB_DQS_DP3"
$PN"AL21"103;
"DDR3_SB_DQS_DP4"
$PN"AN39"104;
"DDR3_SB_DQS_DP5"
$PN"AR33"105;
"DDR3_SB_DQS_DP6"
$PN"AR27"106;
"DDR3_SB_DQS_DP7"
$PN"AH24"107;
"DDR3_SB_DQS_DP8"
$PN"AR21"108;
"DDR3_SB_DQS_DP9"
$PN"AL39"109;
"DDR3_SB_DQS_DN0 \B"
$PN"AJ33"110;
"DDR3_SB_DQS_DN1 \B"
$PN"AJ27"111;
"DDR3_SB_DQS_DN2 \B"
$PN"AB24"112;
"DDR3_SB_DQS_DN3 \B"
$PN"AJ21"113;
"DDR3_SB_DQS_DN4 \B"
$PN"AR39"114;
"DDR3_SB_DQS_DN5 \B"
$PN"AN33"115;
"DDR3_SB_DQS_DN6 \B"
$PN"AN27"116;
"DDR3_SB_DQS_DN7 \B"
$PN"AF24"117;
"DDR3_SB_DQS_DN8 \B"
$PN"AN21"118;
"DDR3_SB_DQS_DN9 \B"
$PN"AJ39"119;
"DDR3_SB_DQ0"
$PN"AL35"90;
"DDR3_SB_DQ1"
$PN"AK34"89;
"DDR3_SB_DQ2"
$PN"AN35"88;
"DDR3_SB_DQ3"
$PN"AP34"87;
"DDR3_SB_DQ4"
$PN"AK32"86;
"DDR3_SB_DQ5"
$PN"AL31"85;
"DDR3_SB_DQ6"
$PN"AP32"84;
"DDR3_SB_DQ7"
$PN"AN31"83;
"DDR3_SB_DQ8"
$PN"AL29"82;
"DDR3_SB_DQ9"
$PN"AK28"81;
"DDR3_SB_DQ10"
$PN"AN29"80;
"DDR3_SB_DQ11"
$PN"AP28"79;
"DDR3_SB_DQ12"
$PN"AK26"78;
"DDR3_SB_DQ13"
$PN"AL25"77;
"DDR3_SB_DQ14"
$PN"AP26"76;
"DDR3_SB_DQ15"
$PN"AN25"75;
"DDR3_SB_DQ16"
$PN"AD26"74;
"DDR3_SB_DQ17"
$PN"AC25"73;
"DDR3_SB_DQ18"
$PN"AF26"72;
"DDR3_SB_DQ19"
$PN"AG25"71;
"DDR3_SB_DQ20"
$PN"AC23"70;
"DDR3_SB_DQ21"
$PN"AD22"69;
"DDR3_SB_DQ22"
$PN"AG23"68;
"DDR3_SB_DQ23"
$PN"AF22"67;
"DDR3_SB_DQ24"
$PN"AL23"66;
"DDR3_SB_DQ25"
$PN"AK22"65;
"DDR3_SB_DQ26"
$PN"AN23"64;
"DDR3_SB_DQ27"
$PN"AP22"63;
"DDR3_SB_DQ28"
$PN"AK20"62;
"DDR3_SB_DQ29"
$PN"AL19"61;
"DDR3_SB_DQ30"
$PN"AP20"60;
"DDR3_SB_DQ31"
$PN"AN19"59;
"DDR3_SB_CS_N0 \B"
$PN"AC41"120;
"DDR3_SB_CS_N1 \B"
$PN"AG41"121;
"DDR3_SB_CS_N2 \B"
$PN"AF40"122;
"DDR3_SB_CS_N3 \B"
$PN"AD40"123;
"DDR3_SB_CA0"
$PN"AK44"124;
"DDR3_SB_CA1"
$PN"AL43"125;
"DDR3_SB_CA2"
$PN"AD44"126;
"DDR3_SB_CA3"
$PN"AF44"127;
"DDR3_SB_CA4"
$PN"AC43"128;
"DDR3_SB_CA5"
$PN"AG43"129;
"DDR3_SB_CA6"
$PN"AB42"130;
"DDR3_SA_PAR"
$PN"AP44"131;
"DDR3_SA_ECC0"
$PN"AL60"58;
"DDR3_SA_ECC1"
$PN"AK59"57;
"DDR3_SA_ECC2"
$PN"AN60"56;
"DDR3_SA_ECC3"
$PN"AP59"55;
"DDR3_SA_ECC4"
$PN"AK57"54;
"DDR3_SA_ECC5"
$PN"AL56"53;
"DDR3_SA_ECC6"
$PN"AP57"52;
"DDR3_SA_ECC7"
$PN"AN56"51;
"DDR3_SA_DQS_DP0"
$PN"AD73"132;
"DDR3_SA_DQS_DP1"
$PN"AL76"133;
"DDR3_SA_DQS_DP2"
$PN"AL70"134;
"DDR3_SA_DQS_DP3"
$PN"AL64"135;
"DDR3_SA_DQS_DP4"
$PN"AL58"136;
"DDR3_SA_DQS_DP5"
$PN"AF73"137;
"DDR3_SA_DQS_DP6"
$PN"AR76"138;
"DDR3_SA_DQS_DP7"
$PN"AR70"139;
"DDR3_SA_DQS_DP8"
$PN"AR64"140;
"DDR3_SA_DQS_DP9"
$PN"AR58"141;
"DDR3_SA_DQS_DN0 \B"
$PN"AB73"142;
"DDR3_SA_DQS_DN1 \B"
$PN"AJ76"143;
"DDR3_SA_DQS_DN2 \B"
$PN"AJ70"144;
"DDR3_SA_DQS_DN3 \B"
$PN"AJ64"145;
"DDR3_SA_DQS_DN4 \B"
$PN"AJ58"146;
"DDR3_SA_DQS_DN5 \B"
$PN"AH73"147;
"DDR3_SA_DQS_DN6 \B"
$PN"AN76"148;
"DDR3_SA_DQS_DN7 \B"
$PN"AN70"149;
"DDR3_SA_DQS_DN8 \B"
$PN"AN64"150;
"DDR3_SA_DQS_DN9 \B"
$PN"AN58"151;
"DDR3_SA_DQ0"
$PN"AD75"50;
"DDR3_SA_DQ1"
$PN"AC74"49;
"DDR3_SA_DQ2"
$PN"AF75"48;
"DDR3_SA_DQ3"
$PN"AG74"47;
"DDR3_SA_DQ4"
$PN"AC72"46;
"DDR3_SA_DQ5"
$PN"AD71"45;
"DDR3_SA_DQ6"
$PN"AG72"44;
"DDR3_SA_DQ7"
$PN"AF71"43;
"DDR3_SA_DQ8"
$PN"AL78"15;
"DDR3_SA_DQ9"
$PN"AK77"42;
"DDR3_SA_DQ10"
$PN"AN78"41;
"DDR3_SA_DQ11"
$PN"AP77"40;
"DDR3_SA_DQ12"
$PN"AK75"39;
"DDR3_SA_DQ13"
$PN"AL74"38;
"DDR3_SA_DQ14"
$PN"AP75"37;
"DDR3_SA_DQ15"
$PN"AN74"36;
"DDR3_SA_DQ16"
$PN"AL72"35;
"DDR3_SA_DQ17"
$PN"AK71"34;
"DDR3_SA_DQ18"
$PN"AN72"33;
"DDR3_SA_DQ19"
$PN"AP71"32;
"DDR3_SA_DQ20"
$PN"AK69"31;
"DDR3_SA_DQ21"
$PN"AL68"30;
"DDR3_SA_DQ22"
$PN"AP69"29;
"DDR3_SA_DQ23"
$PN"AN68"28;
"DDR3_SA_DQ24"
$PN"AL66"27;
"DDR3_SA_DQ25"
$PN"AK65"26;
"DDR3_SA_DQ26"
$PN"AN66"25;
"DDR3_SA_DQ27"
$PN"AP65"24;
"DDR3_SA_DQ28"
$PN"AK63"23;
"DDR3_SA_DQ29"
$PN"AL62"22;
"DDR3_SA_DQ30"
$PN"AP63"21;
"DDR3_SA_DQ31"
$PN"AN62"20;
"DDR3_SA_CS_N0 \B"
$PN"AL54"152;
"DDR3_SA_CS_N1 \B"
$PN"AK53"153;
"DDR3_SA_CS_N2 \B"
$PN"AN54"154;
"DDR3_SA_CS_N3 \B"
$PN"AP53"155;
"DDR3_SA_CA0"
$PN"AJ52"156;
"DDR3_SA_CA1"
$PN"AR52"157;
"DDR3_SA_CA2"
$PN"AK51"158;
"DDR3_SA_CA3"
$PN"AP51"159;
"DDR3_SA_CA4"
$PN"AL50"160;
"DDR3_SA_CA5"
$PN"AN50"161;
"DDR3_SA_CA6"
$PN"AN43"162;
"DDR3_CLK_DP0"
$PN"AL45"19;
"DDR3_CLK_DP1"
$PN"AR45"18;
"DDR3_CLK_DN0 \B"
$PN"AJ45"17;
"DDR3_CLK_DN1 \B"
$PN"AN45"16;
"DDR3_B_RSP0"
$PN"AF51"163;
"DDR3_B_RSP1"
$PN"AG50"164;
"DDR3_A_RSP0"
$PN"AD51"165;
"DDR3_A_RSP1"
$PN"AC50"166;
"DDR3_ALERT_N \B"
$PN"AV47"167;
%"TAP"
"1","(2600,-150)","0","standard","I97";
;
CDS_LIB"standard"
BODY_TYPE"PLUMBING"
HDL_TAP"TRUE";
"B \NAC \NWC"6;
"S \NAC"
BN"0"120;
%"TAP"
"1","(2600,-100)","0","standard","I98";
;
CDS_LIB"standard"
BODY_TYPE"PLUMBING"
HDL_TAP"TRUE";
"B \NAC \NWC"6;
"S \NAC"
BN"1"121;
%"TAP"
"1","(2600,-50)","0","standard","I99";
;
CDS_LIB"standard"
BODY_TYPE"PLUMBING"
HDL_TAP"TRUE";
"B \NAC \NWC"6;
"S \NAC"
BN"2"122;
END.
